(kicad_pcb
	(version 20240108)
	(generator "pcbnew")
	(generator_version "8.0")
	(general
		(thickness 1.586)
		(legacy_teardrops no)
	)
	(paper "A4")
	(title_block
		(title "GMSL Serializer")
		(date "2024-11-27")
		(rev "1.1.1")
		(company "Antmicro Ltd")
		(comment 1 "www.antmicro.com")
		(comment 9 "footprints 49-53 of 117")
	)
	(layers
		(0 "F.Cu" signal)
		(1 "In1.Cu" power)
		(2 "In2.Cu" power)
		(31 "B.Cu" signal)
		(32 "B.Adhes" user "B.Adhesive")
		(33 "F.Adhes" user "F.Adhesive")
		(34 "B.Paste" user)
		(35 "F.Paste" user)
		(36 "B.SilkS" user "B.Silkscreen")
		(37 "F.SilkS" user "F.Silkscreen")
		(38 "B.Mask" user)
		(39 "F.Mask" user)
		(40 "Dwgs.User" user "User.Drawings")
		(41 "Cmts.User" user "User.Comments")
		(42 "Eco1.User" user "User.Eco1")
		(43 "Eco2.User" user "User.Eco2")
		(44 "Edge.Cuts" user)
		(45 "Margin" user)
		(46 "B.CrtYd" user "B.Courtyard")
		(47 "F.CrtYd" user "F.Courtyard")
		(48 "B.Fab" user)
		(49 "F.Fab" user)
	)
	(footprint "antmicro-footprints:C_0402_1005Metric"
		(layer "F.Cu")
		(at 149.53 96.91 -45)
		(descr "Capacitor SMD 0402")
		(tags "capacitor SMD 0402")
		(property "Reference" "C22"
			(at 0.982878 -2.510229 -45)
			(unlocked yes)
			(layer "F.SilkS")
			(effects
				(font
					(size 0.7 0.7)
					(thickness 0.15)
				)
				(justify right bottom)
			)
		)
		(property "Value" "C_100n_0402"
			(at -1.022927 2.155213 135)
			(layer "F.Fab")
			(effects
				(font
					(size 0.7 0.7)
					(thickness 0.15)
				)
				(justify right bottom)
			)
		)
		(property "Footprint" "antmicro-footprints:C_0402_1005Metric"
			(at 0 0 -45)
			(layer "F.Fab")
			(hide yes)
			(effects
				(font
					(size 1.27 1.27)
					(thickness 0.15)
				)
			)
		)
		(property "Datasheet" "https://www.murata.com/products/productdetail?partno=GRM155R61H104KE14%23"
			(at 0 0 -45)
			(layer "F.Fab")
			(hide yes)
			(effects
				(font
					(size 1.27 1.27)
					(thickness 0.15)
				)
			)
		)
		(property "Author" "Antmicro"
			(at -24.729395 134.117959 0)
			(layer "F.Fab")
			(hide yes)
			(effects
				(font
					(size 1 1)
					(thickness 0.15)
				)
			)
		)
		(property "Dielectric" "X5R"
			(at -24.729395 134.117959 0)
			(layer "F.Fab")
			(hide yes)
			(effects
				(font
					(size 1 1)
					(thickness 0.15)
				)
			)
		)
		(property "License" "Apache-2.0"
			(at -24.729395 134.117959 0)
			(layer "F.Fab")
			(hide yes)
			(effects
				(font
					(size 1 1)
					(thickness 0.15)
				)
			)
		)
		(property "MPN" "GRM155R61H104KE14D"
			(at -24.729395 134.117959 0)
			(layer "F.Fab")
			(hide yes)
			(effects
				(font
					(size 1 1)
					(thickness 0.15)
				)
			)
		)
		(property "Manufacturer" "Murata"
			(at -24.729395 134.117959 0)
			(layer "F.Fab")
			(hide yes)
			(effects
				(font
					(size 1 1)
					(thickness 0.15)
				)
			)
		)
		(property "Val" "100n"
			(at -24.729395 134.117959 0)
			(layer "F.Fab")
			(hide yes)
			(effects
				(font
					(size 1 1)
					(thickness 0.15)
				)
			)
		)
		(property "Voltage" "50V"
			(at -24.729395 134.117959 0)
			(layer "F.Fab")
			(hide yes)
			(effects
				(font
					(size 1 1)
					(thickness 0.15)
				)
			)
		)
		(sheetname "Serializer")
		(sheetfile "serializer.kicad_sch")
		(attr smd)
		(fp_poly
			(pts
				(xy -0.925 -0.47) (xy 0.925 -0.47) (xy 0.925 0.47) (xy -0.925 0.47)
			)
			(stroke
				(width 0.05)
				(type default)
			)
			(fill none)
			(layer "F.CrtYd")
		)
		(fp_line
			(start -0.494 0.248)
			(end -0.494 -0.25)
			(stroke
				(width 0.15)
				(type solid)
			)
			(layer "F.Fab")
		)
		(fp_line
			(start -0.494 -0.25)
			(end 0.504 -0.25)
			(stroke
				(width 0.15)
				(type solid)
			)
			(layer "F.Fab")
		)
		(fp_line
			(start 0.504 0.248)
			(end -0.494 0.248)
			(stroke
				(width 0.15)
				(type solid)
			)
			(layer "F.Fab")
		)
		(fp_line
			(start 0.504 -0.25)
			(end 0.504 0.248)
			(stroke
				(width 0.15)
				(type solid)
			)
			(layer "F.Fab")
		)
		(fp_text user "Author: Antmicro"
			(at -0.939 3.399 135)
			(layer "F.Fab")
			(hide yes)
			(effects
				(font
					(size 0.7 0.7)
					(thickness 0.15)
				)
				(justify right bottom)
			)
		)
		(fp_text user "License: Apache-2.0"
			(at -0.939 5.799 135)
			(layer "F.Fab")
			(hide yes)
			(effects
				(font
					(size 0.7 0.7)
					(thickness 0.15)
				)
				(justify right bottom)
			)
		)
		(fp_text user "${REFERENCE}"
			(at -0.939 4.599 135)
			(layer "F.Fab")
			(hide yes)
			(effects
				(font
					(size 0.7 0.7)
					(thickness 0.15)
				)
				(justify right bottom)
			)
		)
		(pad "1" smd roundrect
			(at -0.48 0 315)
			(size 0.59 0.64)
			(layers "F.Cu" "F.Paste" "F.Mask")
			(roundrect_rratio 0.25)
			(net 1 "GND")
			(pintype "passive")
		)
		(pad "2" smd roundrect
			(at 0.48 0 315)
			(size 0.59 0.64)
			(layers "F.Cu" "F.Paste" "F.Mask")
			(roundrect_rratio 0.25)
			(net 12 "+1V2")
			(pintype "passive")
		)
	)
	(footprint "antmicro-footprints:DFN-10_2.5x1mm"
		(layer "F.Cu")
		(at 130.5 113.349)
		(property "Reference" "D4"
			(at -0.75 2.551 0)
			(layer "F.SilkS")
			(effects
				(font
					(size 0.7 0.7)
					(thickness 0.15)
				)
				(justify left bottom)
			)
		)
		(property "Value" "PESD4USB5U-TTS"
			(at 2.032 1.524 0)
			(layer "F.Fab")
			(effects
				(font
					(size 0.7 0.7)
					(thickness 0.15)
				)
				(justify left bottom)
			)
		)
		(property "Footprint" "antmicro-footprints:DFN-10_2.5x1mm"
			(at 0 0 0)
			(layer "F.Fab")
			(hide yes)
			(effects
				(font
					(size 1.27 1.27)
					(thickness 0.15)
				)
			)
		)
		(property "Datasheet" "https://assets.nexperia.com/documents/data-sheet/PESD4USB5U-TTS.pdf"
			(at 0 0 0)
			(layer "F.Fab")
			(hide yes)
			(effects
				(font
					(size 1.27 1.27)
					(thickness 0.15)
				)
			)
		)
		(property "Author" "Antmicro"
			(at 0 0 0)
			(layer "F.Fab")
			(hide yes)
			(effects
				(font
					(size 1 1)
					(thickness 0.15)
				)
			)
		)
		(property "License" "Apache-2.0"
			(at 0 0 0)
			(layer "F.Fab")
			(hide yes)
			(effects
				(font
					(size 1 1)
					(thickness 0.15)
				)
			)
		)
		(property "MPN" "PESD4USB5U-TTS"
			(at 0 0 0)
			(layer "F.Fab")
			(hide yes)
			(effects
				(font
					(size 1 1)
					(thickness 0.15)
				)
			)
		)
		(property "Manufacturer" "Nexperia"
			(at 0 0 0)
			(layer "F.Fab")
			(hide yes)
			(effects
				(font
					(size 1 1)
					(thickness 0.15)
				)
			)
		)
		(sheetname "CSI Connector")
		(sheetfile "CSI.kicad_sch")
		(attr smd)
		(fp_line
			(start -0.4 1.4)
			(end 0.4 1.4)
			(stroke
				(width 0.15)
				(type solid)
			)
			(layer "F.SilkS")
		)
		(fp_line
			(start 0.4 -1.4)
			(end -0.4 -1.4)
			(stroke
				(width 0.15)
				(type solid)
			)
			(layer "F.SilkS")
		)
		(fp_circle
			(center -0.762 -1.27)
			(end -0.712 -1.27)
			(stroke
				(width 0.15)
				(type solid)
			)
			(fill solid)
			(layer "F.SilkS")
		)
		(fp_rect
			(start -0.85 -1.6)
			(end 0.85 1.6)
			(stroke
				(width 0.05)
				(type solid)
			)
			(fill none)
			(layer "F.CrtYd")
		)
		(fp_line
			(start -0.5 -0.9)
			(end -0.5 1.25)
			(stroke
				(width 0.15)
				(type solid)
			)
			(layer "F.Fab")
		)
		(fp_line
			(start -0.5 1.25)
			(end 0.5 1.25)
			(stroke
				(width 0.15)
				(type solid)
			)
			(layer "F.Fab")
		)
		(fp_line
			(start -0.15 -1.25)
			(end -0.5 -0.9)
			(stroke
				(width 0.15)
				(type solid)
			)
			(layer "F.Fab")
		)
		(fp_line
			(start 0.5 -1.25)
			(end -0.15 -1.25)
			(stroke
				(width 0.15)
				(type solid)
			)
			(layer "F.Fab")
		)
		(fp_line
			(start 0.5 1.25)
			(end 0.5 -1.25)
			(stroke
				(width 0.15)
				(type solid)
			)
			(layer "F.Fab")
		)
		(fp_text user "License: Apache-2.0"
			(at -0.95 5.924 0)
			(layer "F.Fab")
			(hide yes)
			(effects
				(font
					(size 0.7 0.7)
					(thickness 0.15)
				)
				(justify left bottom)
			)
		)
		(fp_text user "Author: Antmicro"
			(at -0.95 4.724 0)
			(layer "F.Fab")
			(hide yes)
			(effects
				(font
					(size 0.7 0.7)
					(thickness 0.15)
				)
				(justify left bottom)
			)
		)
		(fp_text user "${REFERENCE}"
			(at -0.95 3.524 0)
			(layer "F.Fab")
			(hide yes)
			(effects
				(font
					(size 0.7 0.7)
					(thickness 0.15)
				)
				(justify left bottom)
			)
		)
		(pad "1" smd roundrect
			(at -0.425 -1 270)
			(size 0.2 0.6)
			(layers "F.Cu" "F.Paste" "F.Mask")
			(roundrect_rratio 0.25)
			(net 10 "+3V3")
			(pinfunction "1")
			(pintype "passive")
			(solder_mask_margin 0.05)
		)
		(pad "2" smd roundrect
			(at -0.425 -0.5 270)
			(size 0.2 0.6)
			(layers "F.Cu" "F.Paste" "F.Mask")
			(roundrect_rratio 0.25)
			(net 10 "+3V3")
			(pinfunction "2")
			(pintype "passive")
			(solder_mask_margin 0.05)
		)
		(pad "3" smd roundrect
			(at -0.425 0 270)
			(size 0.4 0.6)
			(layers "F.Cu" "F.Paste" "F.Mask")
			(roundrect_rratio 0.25)
			(net 1 "GND")
			(pinfunction "3")
			(pintype "passive")
			(solder_mask_margin 0.05)
		)
		(pad "4" smd roundrect
			(at -0.425 0.5 270)
			(size 0.2 0.6)
			(layers "F.Cu" "F.Paste" "F.Mask")
			(roundrect_rratio 0.25)
			(net 9 "+5V")
			(pinfunction "4")
			(pintype "passive")
			(solder_mask_margin 0.05)
		)
		(pad "5" smd roundrect
			(at -0.425 1 270)
			(size 0.2 0.6)
			(layers "F.Cu" "F.Paste" "F.Mask")
			(roundrect_rratio 0.25)
			(net 9 "+5V")
			(pinfunction "5")
			(pintype "passive")
			(solder_mask_margin 0.05)
		)
		(pad "6" smd roundrect
			(at 0.425 1 270)
			(size 0.2 0.6)
			(layers "F.Cu" "F.Paste" "F.Mask")
			(roundrect_rratio 0.25)
			(net 9 "+5V")
			(pinfunction "6")
			(pintype "passive")
			(solder_mask_margin 0.05)
		)
		(pad "7" smd roundrect
			(at 0.425 0.5 270)
			(size 0.2 0.6)
			(layers "F.Cu" "F.Paste" "F.Mask")
			(roundrect_rratio 0.25)
			(net 9 "+5V")
			(pinfunction "7")
			(pintype "passive")
			(solder_mask_margin 0.05)
		)
		(pad "8" smd roundrect
			(at 0.425 0 270)
			(size 0.4 0.6)
			(layers "F.Cu" "F.Paste" "F.Mask")
			(roundrect_rratio 0.25)
			(net 1 "GND")
			(pinfunction "8")
			(pintype "passive")
			(solder_mask_margin 0.05)
		)
		(pad "9" smd roundrect
			(at 0.425 -0.5 270)
			(size 0.2 0.6)
			(layers "F.Cu" "F.Paste" "F.Mask")
			(roundrect_rratio 0.25)
			(net 10 "+3V3")
			(pinfunction "9")
			(pintype "passive")
			(solder_mask_margin 0.05)
		)
		(pad "10" smd roundrect
			(at 0.425 -1 270)
			(size 0.2 0.6)
			(layers "F.Cu" "F.Paste" "F.Mask")
			(roundrect_rratio 0.25)
			(net 10 "+3V3")
			(pinfunction "10")
			(pintype "passive")
			(solder_mask_margin 0.05)
		)
	)
	(footprint "antmicro-footprints:MP_Pad6mm_Drill3mm"
		(layer "F.Cu")
		(at 127.15 81.35)
		(property "Reference" "MP4"
			(at 0 -3.2 0)
			(layer "F.SilkS")
			(hide yes)
			(effects
				(font
					(size 0.7 0.7)
					(thickness 0.15)
				)
				(justify left bottom)
			)
		)
		(property "Value" "MP_Pad6mm_Drill3mm"
			(at 0 3.9 0)
			(layer "F.Fab")
			(effects
				(font
					(size 0.7 0.7)
					(thickness 0.15)
				)
				(justify left bottom)
			)
		)
		(property "Footprint" "antmicro-footprints:MP_Pad6mm_Drill3mm"
			(at 0 0 0)
			(layer "F.Fab")
			(hide yes)
			(effects
				(font
					(size 1.27 1.27)
					(thickness 0.15)
				)
			)
		)
		(property "Author" "Antmicro"
			(at 0 0 0)
			(layer "F.Fab")
			(hide yes)
			(effects
				(font
					(size 1 1)
					(thickness 0.15)
				)
			)
		)
		(property "License" "Apache-2.0"
			(at 0 0 0)
			(layer "F.Fab")
			(hide yes)
			(effects
				(font
					(size 1 1)
					(thickness 0.15)
				)
			)
		)
		(sheetname "Root")
		(sheetfile "gmsl-serializer.kicad_sch")
		(attr exclude_from_pos_files exclude_from_bom)
		(fp_circle
			(center 0 0)
			(end 3.25 0)
			(stroke
				(width 0.05)
				(type default)
			)
			(fill none)
			(layer "F.CrtYd")
		)
		(fp_text user "${REFERENCE}"
			(at -0.178 6.025 0)
			(layer "F.Fab")
			(hide yes)
			(effects
				(font
					(size 0.7 0.7)
					(thickness 0.15)
				)
				(justify left bottom)
			)
		)
		(fp_text user "Author: Antmicro"
			(at -0.178 7.225 0)
			(layer "F.Fab")
			(hide yes)
			(effects
				(font
					(size 0.7 0.7)
					(thickness 0.15)
				)
				(justify left bottom)
			)
		)
		(fp_text user "License: Apache-2.0"
			(at -0.178 8.425 0)
			(layer "F.Fab")
			(hide yes)
			(effects
				(font
					(size 0.7 0.7)
					(thickness 0.15)
				)
				(justify left bottom)
			)
		)
		(pad "1" thru_hole circle
			(at 0 0)
			(size 6 6)
			(drill 3)
			(layers "*.Cu" "*.Mask")
			(remove_unused_layers no)
			(net 1 "GND")
			(pintype "passive")
			(solder_paste_margin_ratio -1)
		)
	)
	(footprint "antmicro-footprints:TP_SMD_1.5mm"
		(layer "F.Cu")
		(at 142.25 118)
		(property "Reference" "TP1"
			(at -1 -0.964 0)
			(layer "F.SilkS")
			(hide yes)
			(effects
				(font
					(size 0.7 0.7)
					(thickness 0.15)
				)
				(justify left bottom)
			)
		)
		(property "Value" "TP_1.5mm_SMD"
			(at 0 1.7 0)
			(layer "F.Fab")
			(effects
				(font
					(size 0.7 0.7)
					(thickness 0.15)
				)
				(justify left bottom)
			)
		)
		(property "Footprint" "antmicro-footprints:TP_SMD_1.5mm"
			(at 0 0 0)
			(layer "F.Fab")
			(hide yes)
			(effects
				(font
					(size 1.27 1.27)
					(thickness 0.15)
				)
			)
		)
		(property "Author" "Antmicro"
			(at 0 0 0)
			(layer "F.Fab")
			(hide yes)
			(effects
				(font
					(size 1 1)
					(thickness 0.15)
				)
			)
		)
		(property "License" "Apache-2.0"
			(at 0 0 0)
			(layer "F.Fab")
			(hide yes)
			(effects
				(font
					(size 1 1)
					(thickness 0.15)
				)
			)
		)
		(property "MPN" ""
			(at 0 0 0)
			(layer "F.Fab")
			(hide yes)
			(effects
				(font
					(size 1 1)
					(thickness 0.15)
				)
			)
		)
		(property "Manufacturer" ""
			(at 0 0 0)
			(layer "F.Fab")
			(hide yes)
			(effects
				(font
					(size 1 1)
					(thickness 0.15)
				)
			)
		)
		(sheetname "Supply")
		(sheetfile "supply.kicad_sch")
		(attr exclude_from_pos_files exclude_from_bom)
		(fp_circle
			(center 0 0)
			(end 0.85 0)
			(stroke
				(width 0.05)
				(type default)
			)
			(fill none)
			(layer "F.CrtYd")
		)
		(fp_text user "License: Apache-2.0"
			(at -0.7 5.301 0)
			(layer "F.Fab")
			(hide yes)
			(effects
				(font
					(size 0.7 0.7)
					(thickness 0.15)
				)
				(justify left bottom)
			)
		)
		(fp_text user "${REFERENCE}"
			(at -0.7 2.9 0)
			(layer "F.Fab")
			(hide yes)
			(effects
				(font
					(size 0.7 0.7)
					(thickness 0.15)
				)
				(justify left bottom)
			)
		)
		(fp_text user "Author: Antmicro"
			(at -0.7 4.101 0)
			(layer "F.Fab")
			(hide yes)
			(effects
				(font
					(size 0.7 0.7)
					(thickness 0.15)
				)
				(justify left bottom)
			)
		)
		(pad "1" smd circle
			(at 0 0 270)
			(size 1.5 1.5)
			(layers "F.Cu" "F.Mask")
			(net 9 "+5V")
			(pinfunction "1")
			(pintype "passive")
		)
	)
	(footprint "antmicro-footprints:R_0402_1005Metric"
		(layer "F.Cu")
		(at 151.7 115.355 -90)
		(descr "Resistor SMD 0402")
		(tags "resistor SMD 0402")
		(property "Reference" "R34"
			(at -1.122484 -1.35 90)
			(layer "F.SilkS")
			(effects
				(font
					(size 0.7 0.7)
					(thickness 0.15)
				)
				(justify right bottom)
			)
		)
		(property "Value" "R_100k_0402"
			(at -1.011843 1.772047 90)
			(layer "F.Fab")
			(effects
				(font
					(size 0.7 0.7)
					(thickness 0.15)
				)
				(justify right bottom)
			)
		)
		(property "Footprint" "antmicro-footprints:R_0402_1005Metric"
			(at 0 0 -90)
			(layer "F.Fab")
			(hide yes)
			(effects
				(font
					(size 1.27 1.27)
					(thickness 0.15)
				)
			)
		)
		(property "Datasheet" "https://www.bourns.com/docs/product-datasheets/cr.pdf"
			(at 0 0 -90)
			(layer "F.Fab")
			(hide yes)
			(effects
				(font
					(size 1.27 1.27)
					(thickness 0.15)
				)
			)
		)
		(property "Author" "Antmicro"
			(at 36.345 267.055 0)
			(layer "F.Fab")
			(hide yes)
			(effects
				(font
					(size 1 1)
					(thickness 0.15)
				)
			)
		)
		(property "License" "Apache-2.0"
			(at 36.345 267.055 0)
			(layer "F.Fab")
			(hide yes)
			(effects
				(font
					(size 1 1)
					(thickness 0.15)
				)
			)
		)
		(property "MPN" "CR0402-FX-1003GLF"
			(at 36.345 267.055 0)
			(layer "F.Fab")
			(hide yes)
			(effects
				(font
					(size 1 1)
					(thickness 0.15)
				)
			)
		)
		(property "Manufacturer" "Bourns"
			(at 36.345 267.055 0)
			(layer "F.Fab")
			(hide yes)
			(effects
				(font
					(size 1 1)
					(thickness 0.15)
				)
			)
		)
		(property "Tolerance" "1%"
			(at 36.345 267.055 0)
			(layer "F.Fab")
			(hide yes)
			(effects
				(font
					(size 1 1)
					(thickness 0.15)
				)
			)
		)
		(property "Val" "100k"
			(at 36.345 267.055 0)
			(layer "F.Fab")
			(hide yes)
			(effects
				(font
					(size 1 1)
					(thickness 0.15)
				)
			)
		)
		(sheetname "Supply")
		(sheetfile "supply.kicad_sch")
		(attr smd)
		(fp_rect
			(start -0.925 -0.47)
			(end 0.925 0.47)
			(stroke
				(width 0.05)
				(type default)
			)
			(fill none)
			(layer "F.CrtYd")
		)
		(fp_rect
			(start -0.5 -0.25)
			(end 0.5 0.25)
			(stroke
				(width 0.15)
				(type solid)
			)
			(fill none)
			(layer "F.Fab")
		)
		(fp_text user "License: Apache-2.0"
			(at -0.95 5.169 90)
			(layer "F.Fab")
			(hide yes)
			(effects
				(font
					(size 0.7 0.7)
					(thickness 0.15)
				)
				(justify right bottom)
			)
		)
		(fp_text user "Author: Antmicro"
			(at -0.95 4.169 90)
			(layer "F.Fab")
			(hide yes)
			(effects
				(font
					(size 0.7 0.7)
					(thickness 0.15)
				)
				(justify right bottom)
			)
		)
		(fp_text user "${REFERENCE}"
			(at -0.95 3.168 90)
			(layer "F.Fab")
			(hide yes)
			(effects
				(font
					(size 0.7 0.7)
					(thickness 0.15)
				)
				(justify right bottom)
			)
		)
		(pad "1" smd roundrect
			(at -0.48 0 270)
			(size 0.59 0.64)
			(layers "F.Cu" "F.Paste" "F.Mask")
			(roundrect_rratio 0.25)
			(net 1 "GND")
			(pintype "passive")
		)
		(pad "2" smd roundrect
			(at 0.48 0 270)
			(size 0.59 0.64)
			(layers "F.Cu" "F.Paste" "F.Mask")
			(roundrect_rratio 0.25)
			(net 12 "+1V2")
			(pintype "passive")
		)
	)
)
